# T6G (Grand Teton) — schematic parts with pin connectivity, parts 5189–5341 of 8303; source: Cadence DE-HDL packaged netlist (pstxprt.dat, pstxnet.dat, pstchip.dat)

R465  Q_RES  49.9 1% CHIP  pkg 0402LF  page 29 : 1 = SPI_CPU0_D1 ; 2 = SPI_CPU0_R_D1
R466  Q_RES  33 5% CHIP  pkg 0402LF  page 29 : 1 = SPI_CPU0_D2 ; 2 = SPI_CPU0_R_D2
R467  Q_RES  33 5% CHIP  pkg 0402LF  page 29 : 1 = SPI_CPU0_D3 ; 2 = SPI_CPU0_R_D3
R468  Q_RES  33 5% CHIP  pkg 0402LF  page 29 : 1 = ESPI_CPU0_D0 ; 2 = ESPI_CPU0_R_D0
R469  Q_RES  33 5% CHIP  pkg 0402LF  page 29 : 1 = ESPI_CPU0_D1 ; 2 = ESPI_CPU0_R_D1
R470  Q_RES  33 5% CHIP  pkg 0402LF  page 29 : 1 = ESPI_CPU0_D2 ; 2 = ESPI_CPU0_R_D2
R471  Q_RES  33 5% CHIP  pkg 0402LF  page 29 : 1 = ESPI_CPU0_D3 ; 2 = ESPI_CPU0_R_D3
R472  Q_RES  33 5% EMPTY  pkg 0402LF  page 29 : 1 = ESPI_CPU0_ALERT_P0_N ; 2 = ESPI_CPU0_R_ALERT_N
R473  Q_RES  0 5% CHIP  pkg 0402LF  page 29 : 1 = CLK_ESPI_CPU0_CLK1 ; 2 = CLK_ESPI_CPU0_R_CLK1
R474  Q_RES  0 5% CHIP  pkg 0402LF  page 29 : 1 = RST_ESPI_CPU0_RSTOUT_N ; 2 = RST_ESPI_CPU0_R_RSTOUT_N
R475  Q_RES  33 5% CHIP  pkg 0402LF  page 29 : 1 = SPI_CPU0_TPM_CS_N ; 2 = SPI_CPU0_R_TPM_CS_N
R476  Q_RES  33 5% CHIP  pkg 0402LF  page 172 : 1 = CPU0_XTRIG_L6 ; 2 = HDT_CPU0_XTRIG_L6
R477  Q_RES  33 5% CHIP  pkg 0402LF  page 172 : 1 = CPU0_XTRIG_L7 ; 2 = HDT_CPU0_XTRIG_L7
R478  Q_RES  33 5% CHIP  pkg 0402LF  page 172 : 1 = CPU0_XTRIG_L5 ; 2 = HDT_CPU0_XTRIG_L5
R479  Q_RES  10K 1% CHIP  pkg 0402LF  page 188 : 1 = P5V ; 2 = PWRGD_P5V_R
R480  Q_RES  100K 1% CHIP  pkg 0402LF  page 188 : 1 = PWRGD_P5V_R ; 2 = GND
R481  Q_RES  0 5% CHIP  pkg 0402LF  page 27 : 1 = CPU0_XTRIG_L4 ; 2 = CPU0_XTRIG_R1_L4
R482  Q_RES  0 5% CHIP  pkg 0402LF  page 188 : 1 = PWRGD_P5V_R ; 2 = PWRGD_P5V_R1
R483  Q_RES  0 5% CHIP  pkg 0402LF  page 27 : 1 = CPU0_XTRIG_L5 ; 2 = CPU0_XTRIG_R1_L5
R484  Q_RES  0 5% CHIP  pkg 0402LF  page 27 : 1 = CPU0_XTRIG_L6 ; 2 = CPU0_XTRIG_R1_L6
R485  Q_RES  0 5% CHIP  pkg 0402LF  page 27 : 1 = CPU0_XTRIG_L7 ; 2 = CPU0_XTRIG_R1_L7
R486  Q_RES  0 5% CHIP  pkg 0402LF  page 54 : 1 = CPU1_XTRIG_R2_L4 ; 2 = CPU1_XTRIG_L4
R487  Q_RES  0 5% CHIP  pkg 0402LF  page 188 : 1 = SW_P3V3_EN ; 2 = SW_P3V3_EN_R
R488  Q_RES  33 5% CHIP  pkg 0402LF  page 54 : 1 = CPU1_THERMTRIP_N ; 2 = CPU1_THERMTRIP_R_N
R489  Q_RES  33 5% CHIP  pkg 0402LF  page 27 : 1 = CPU0_THERMTRIP_N ; 2 = CPU0_THERMTRIP_R_N
R490  Q_RES  0 5% EMPTY  pkg 0402LF  page 188 : 1 = PWRGD_P5V_R ; 2 = SW_P3V3_EN_R
R491  Q_RES  4.7K 5% EMPTY  pkg 0402LF  page 55 : 1 = GND ; 2 = CPU1_PWRGD_OUT
R492  Q_RES  4.7K 5% CHIP  pkg 0402LF  page 188 : 1 = P3V3_AUX ; 2 = PWRGD_P5V_R_N
R493  Q_RES  0 5% CHIP  pkg 0402LF  page 80 : 1 = SMB_CPU0_4_XLTR_R_SDA ; 2 = SMB_CPU0_4_XLTR_SDA
R494  Q_RES  0 5% CHIP  pkg 0402LF  page 188 : 1 = PWRGD_P5V_R_N ; 2 = PWRGD_P5V_N
R495  Q_RES  4.7K 5% CHIP  pkg 0402LF  page 34 : 1 = PVDD18_S5_P0 ; 2 = SMB_CPU0_4_SCL
R496  Q_RES  10K 1% EMPTY  pkg 0402LF  page 188 : 1 = P3V3_AUX ; 2 = SW_P3V3_EN
R497  Q_RES  33 5% CHIP  pkg 0402LF  page 54 : 1 = APML_CPU1_ALERT_N ; 2 = APML_CPU1_ALERT_R_N
R498  Q_RES  2.2K 5% CHIP  pkg 0402LF  page 34 : 1 = PVDD18_S5_P0 ; 2 = SMB_CPU0_4_SDA
R499  Q_RES  4.7K 5% CHIP  pkg 0402LF  page 34 : 1 = P3V3_AUX ; 2 = SMB_CPU0_4_XLTR_SCL
R500  Q_RES  15 1% CHIP  pkg 0402LF  page 37 : 1 = M_A_CPU1_ALERT_N ; 2 = M_A_CPU1_ALERT_R_N
R501  Q_RES  15 1% CHIP  pkg 0402LF  page 38 : 1 = M_B_CPU1_ALERT_N ; 2 = M_B_CPU1_ALERT_R_N
R502  Q_RES  15 1% CHIP  pkg 0402LF  page 39 : 1 = M_C_CPU1_ALERT_N ; 2 = M_C_CPU1_ALERT_R_N
R503  Q_RES  15 1% CHIP  pkg 0402LF  page 40 : 1 = M_D_CPU1_ALERT_N ; 2 = M_D_CPU1_ALERT_R_N
R504  Q_RES  15 1% CHIP  pkg 0402LF  page 41 : 1 = M_E_CPU1_ALERT_N ; 2 = M_E_CPU1_ALERT_R_N
R505  Q_RES  15 1% CHIP  pkg 0402LF  page 42 : 1 = M_F_CPU1_ALERT_N ; 2 = M_F_CPU1_ALERT_R_N
R506  Q_RES  15 1% CHIP  pkg 0402LF  page 43 : 1 = M_G_CPU1_ALERT_N ; 2 = M_G_CPU1_ALERT_R_N
R507  Q_RES  15 1% CHIP  pkg 0402LF  page 44 : 1 = M_H_CPU1_ALERT_N ; 2 = M_H_CPU1_ALERT_R_N
R508  Q_RES  15 1% CHIP  pkg 0402LF  page 45 : 1 = M_I_CPU1_ALERT_N ; 2 = M_I_CPU1_ALERT_R_N
R509  Q_RES  15 1% CHIP  pkg 0402LF  page 46 : 1 = M_J_CPU1_ALERT_N ; 2 = M_J_CPU1_ALERT_R_N
R510  Q_RES  15 1% CHIP  pkg 0402LF  page 47 : 1 = M_K_CPU1_ALERT_N ; 2 = M_K_CPU1_ALERT_R_N
R511  Q_RES  15 1% CHIP  pkg 0402LF  page 48 : 1 = M_L_CPU1_ALERT_N ; 2 = M_L_CPU1_ALERT_R_N
R512  Q_RES  2.2K 5% CHIP  pkg 0402LF  page 54 : 1 = P3V3_AUX ; 2 = CPU1_CORETYPE2
R513  Q_RES  2.2K 5% CHIP  pkg 0402LF  page 54 : 1 = P3V3_AUX ; 2 = CPU1_SP5R4
R514  Q_RES  2.2K 5% CHIP  pkg 0402LF  page 54 : 1 = P3V3_AUX ; 2 = CPU1_CORETYPE1
R515  Q_RES  2.2K 5% CHIP  pkg 0402LF  page 54 : 1 = P3V3_AUX ; 2 = CPU1_SP5R3
R516  Q_RES  2.2K 5% CHIP  pkg 0402LF  page 54 : 1 = P3V3_AUX ; 2 = CPU1_CORETYPE0
R517  Q_RES  2.2K 5% CHIP  pkg 0402LF  page 54 : 1 = P3V3_AUX ; 2 = CPU1_SP5R2
R518  Q_RES  2.2K 5% CHIP  pkg 0402LF  page 54 : 1 = PVDD18_S5_P1 ; 2 = CPU1_SA0
R519  Q_RES  2.2K 5% EMPTY  pkg 0402LF  page 54 : 1 = CPU1_SA0 ; 2 = GND
R520  Q_RES  2.2K 5% CHIP  pkg 0402LF  page 54 : 1 = CPU1_PROCHOT_N ; 2 = PVDD18_S5_P1
R521  Q_RES  2.2K 5% CHIP  pkg 0402LF  page 54 : 1 = CPU1_SA1 ; 2 = GND
R522  Q_RES  2.2K 5% CHIP  pkg 0402LF  page 54 : 1 = P3V3_AUX ; 2 = CPU1_SP5R1
R523  Q_RES  1K 1% CHIP  pkg 0402LF  page 54 : 1 = PVDD18_S5_P1 ; 2 = JTAG_CPU1_TDO
R524  Q_RES  1K 1% CHIP  pkg 0402LF  page 54 : 1 = PVDD18_S5_P1 ; 2 = JTAG_CPU1_TDI
R525  Q_RES  1K 1% CHIP  pkg 0402LF  page 54 : 1 = PVDD18_S5_P1 ; 2 = JTAG_CPU1_TRST_N
R526  Q_RES  1K 1% CHIP  pkg 0402LF  page 54 : 1 = PVDD18_S5_P1 ; 2 = JTAG_CPU1_TCK
R527  Q_RES  1K 1% CHIP  pkg 0402LF  page 54 : 1 = PVDD18_S5_P1 ; 2 = JTAG_CPU1_TMS
R528  Q_RES  1K 1% CHIP  pkg 0402LF  page 54 : 1 = PVDD18_S5_P1 ; 2 = JTAG_CPU1_DBREQ_N
R529  Q_RES  0 5% CHIP  pkg 0402LF  page 54 : 1 = JTAG_CPU1_R_TDO ; 2 = JTAG_CPU1_TDO
R530  Q_RES  0 5% CHIP  pkg 0402LF  page 85 : 1 = RST_CPU0_RESETL_N ; 2 = RST_CPU1_RESETL_N
R531  Q_RES  2.2K 5% CHIP  pkg 0402LF  page 54 : 1 = CPU1_BP0 ; 2 = PVDD18_S5_P1
R532  Q_RES  2.2K 5% CHIP  pkg 0402LF  page 54 : 1 = CPU1_BP1 ; 2 = PVDD18_S5_P1
R533  Q_RES  2.2K 5% CHIP  pkg 0402LF  page 54 : 1 = CPU1_BP2 ; 2 = PVDD18_S5_P1
R534  Q_RES  2.2K 5% CHIP  pkg 0402LF  page 54 : 1 = CPU1_BP3 ; 2 = PVDD18_S5_P1
R535  Q_RES  2.2K 5% CHIP  pkg 0402LF  page 54 : 1 = APML_CPU1_ALERT_N ; 2 = PVDD18_S5_P1
R536  Q_RES  2.2K 5% EMPTY  pkg 0402LF  page 54 : 1 = CPU1_THERMTRIP_N ; 2 = PVDD18_S5_P1
R537  Q_RES  2.2K 5% CHIP  pkg 0402LF  page 54 : 1 = CPU1_XTRIG_L4 ; 2 = PVDD18_S5_P1
R538  Q_RES  2.2K 5% CHIP  pkg 0402LF  page 54 : 1 = CPU1_XTRIG_L5 ; 2 = PVDD18_S5_P1
R539  Q_RES  2.2K 5% CHIP  pkg 0402LF  page 54 : 1 = CPU1_XTRIG_L6 ; 2 = PVDD18_S5_P1
R540  Q_RES  2.2K 5% CHIP  pkg 0402LF  page 54 : 1 = CPU1_XTRIG_L7 ; 2 = PVDD18_S5_P1
R541  Q_RES  1K 1% EMPTY  pkg 0402LF  page 55 : 1 = PVDD11_S3_P1 ; 2 = I3C_1_SPD_DDRGL_CPU1_R_SDA
R542  Q_RES  1K 1% EMPTY  pkg 0402LF  page 55 : 1 = PVDD11_S3_P1 ; 2 = I3C_1_SPD_DDRGL_CPU1_R_SCL
R543  Q_RES  1K 1% EMPTY  pkg 0402LF  page 55 : 1 = PVDD11_S3_P1 ; 2 = I3C_0_SPD_DDRAF_CPU1_R_SDA
R544  Q_RES  4.7K 5% CHIP  pkg 0402LF  page 55 : 1 = IRQ_CPU_BMC_NMI_N ; 2 = PVDD18_S5_P1
R545  Q_RES  4.7K 5% CHIP  pkg 0402LF  page 55 : 1 = FM_BMC_READY_N ; 2 = PVDD18_S5_P1
R546  Q_RES  4.7K 5% CHIP  pkg 0402LF  page 55 : 1 = FM_BMC_TPM_PRES_N ; 2 = PVDD18_S5_P1
R547  Q_RES  4.7K 5% CHIP  pkg 0402LF  page 55 : 1 = FM_CPU1_BMC_RST_N ; 2 = PVDD18_S5_P1
R548  Q_RES  4.7K 5% EMPTY  pkg 0402LF  page 55 : 1 = CPU1_SLP_S5_N ; 2 = PVDD18_S5_P1
R549  Q_RES  4.7K 5% EMPTY  pkg 0402LF  page 55 : 1 = CPU1_SLP_S3_N ; 2 = PVDD18_S5_P1
R550  Q_RES  4.7K 5% CHIP  pkg 0402LF  page 55 : 1 = CPU1_SMERR_N ; 2 = PVDD18_S5_P1
R551  Q_RES  4.7K 5% CHIP  pkg 0402LF  page 55 : 1 = CPU1_SPD_HOST_CTRL_N ; 2 = PVDD18_S5_P1
R552  Q_RES  4.7K 5% CHIP  pkg 0402LF  page 188 : 1 = P3V3_AUX ; 2 = PWRGD_P5V_R2
R553  Q_RES  4.7K 5% CHIP  pkg 0402LF  page 55 : 1 = CPU1_NV_SAVE_N ; 2 = PVDD18_S5_P1
R554  Q_RES  100K 1% CHIP  pkg 0402LF  page 188 : 1 = P12V_AUX ; 2 = SW_P3V3_EN_N
R555  Q_RES  1 1% CHIP  pkg 0603LF  page 183 : 1 = P3V3_9ZXL045_P1 ; 2 = P3V3_9ZXL045_P1_VDDR
R556  Q_RES  1K 1% EMPTY  pkg 0402LF  page 55 : 1 = PVDD18_S5_P1 ; 2 = RST_CPU1_RESETL_N
R557  Q_RES  1K 1% EMPTY  pkg 0402LF  page 55 : 1 = PVDD18_S5_P1 ; 2 = PWRGD_CPU1_PWROK
R558  Q_RES  4.7K 5% EMPTY  pkg 0402LF  page 55 : 1 = CPU1_FORCE_SELFREFRESH ; 2 = PVDD18_S5_P1
R559  Q_RES  2.2K 5% CHIP  pkg 0402LF  page 55 : 1 = PVDD18_S5_P1 ; 2 = RST_CPU1_SYS_N
R560  Q_RES  10K 1% CHIP  pkg 0402LF  page 183 : 1 = P3V3_AUX ; 2 = FM_9ZXL045_P1_DEV_EN
R561  Q_RES  0 5% CHIP  pkg 0402LF  page 134 : 1 = P12V_OCP_SFF_BUF_EN_R ; 2 = P12V_OCP_EN_1_R
R562  Q_RES  2.2K 5% CHIP  pkg 0402LF  page 55 : 1 = PVDD18_S5_P1 ; 2 = CPU1_NMI_SYNC_FLOOD_N
R563  Q_RES  1K 1% EMPTY  pkg 0402LF  page 55 : 1 = PVDD11_S3_P1 ; 2 = I3C_0_SPD_DDRAF_CPU1_R_SCL
R564  Q_RES  0 5% CHIP  pkg 0402LF  page 159 : 1 = I3C_0_SPD_DDRAF_CPU1_SCL ; 2 = I3C_0_SPD_DDRAF_CPU1_R_SCL
R565  Q_RES  0 5% CHIP  pkg 0402LF  page 159 : 1 = I3C_0_SPD_DDRAF_CPU1_SDA ; 2 = I3C_0_SPD_DDRAF_CPU1_R_SDA
R566  Q_RES  0 5% CHIP  pkg 0402LF  page 159 : 1 = I3C_1_SPD_DDRGL_CPU1_SCL ; 2 = I3C_1_SPD_DDRGL_CPU1_R_SCL
R567  Q_RES  0 5% CHIP  pkg 0402LF  page 159 : 1 = I3C_1_SPD_DDRGL_CPU1_SDA ; 2 = I3C_1_SPD_DDRGL_CPU1_R_SDA
R568  Q_RES  10K 1% CHIP  pkg 0402LF  page 188 : 1 = P12V_AUX ; 2 = SW_P3V3_EN_ISO_R
R569  Q_RES  1K 1% CHIP  pkg 0402LF  page 188 : 1 = SW_P3V3_EN_ISO_R ; 2 = SW_P3V3_EN_ISO
R570  Q_RES  0 5% CHIP  pkg 0402LF  page 55 : 1 = CPU1_SPD_HOST_CTRL_N ; 2 = CPU1_SPD_HOST_CTRL_R_N
R571  Q_RES  10M 1% CHIP  pkg 0402LF  page 55 : 1 = XTAL_CPU1_X48M_X1 ; 2 = XTAL_CPU1_X48M_X2_R
R572  Q_RES  20M 1% CHIP  pkg 0402LF  page 55 : 1 = XTAL_CPU1_R_X32K_X1 ; 2 = XTAL_CPU1_R_X32K_X2
R573  Q_RES  0 5% CHIP  pkg 0402LF  page 55 : 1 = CLK_CPU0_RTCCLK ; 2 = XTAL_CPU1_X32K_X1
R574  Q_RES  0 5% EMPTY  pkg 0402LF  page 55 : 1 = XTAL_CPU1_R_X32K_X1 ; 2 = XTAL_CPU1_X32K_X1
R575  Q_RES  0 5% EMPTY  pkg 0402LF  page 55 : 1 = XTAL_CPU1_R_X32K_X2 ; 2 = XTAL_CPU1_X32K_X2
R576  Q_RES  0 5% CHIP  pkg 0402LF  page 134 : 1 = HP_LVC3_OCP_V3_1_PRSNT2_N_R ; 2 = HP_LVC3_OCP_SFF_PRSNT2_N
R577  Q_RES  10K 1% CHIP  pkg 0402LF  page 134 : 1 = P3V3_AUX ; 2 = HP_LVC3_OCP_SFF_PRSNT2_N
R578  Q_RES  4.75K 1% EMPTY  pkg 0402LF  page 183 : 1 = P3V3_AUX ; 2 = CLK_9ZXL045_P1_SADR0
R579  Q_RES  4.75K 1% CHIP  pkg 0402LF  page 183 : 1 = CLK_9ZXL045_P1_SADR0 ; 2 = GND
R580  Q_RES  10K 1% CHIP  pkg 0402LF  page 183 : 1 = P3V3_AUX ; 2 = CLK_9ZXL045_P1_HIBW
R581  Q_RES  4.7K 5% EMPTY  pkg 0402LF  page 28 : 1 = RST_CPU0_RSMRST_N ; 2 = PVDD18_S5_P0
R582  Q_RES  4.7K 5% EMPTY  pkg 0402LF  page 28 : 1 = GND ; 2 = RST_CPU0_RSMRST_N
R583  Q_RES  4.7K 5% EMPTY  pkg 0402LF  page 55 : 1 = RST_CPU1_RSMRST_N ; 2 = PVDD18_S5_P1
R584  Q_RES  4.7K 5% EMPTY  pkg 0402LF  page 55 : 1 = GND ; 2 = RST_CPU1_RSMRST_N
R585  Q_RES  10K 1% CHIP  pkg 0402LF  page 183 : 1 = CLK_9ZXL045_P1_HIBW ; 2 = GND
R586  Q_RES  1 1% CHIP  pkg 0603LF  page 183 : 1 = P3V3_9ZXL045_P1 ; 2 = P3V3_9ZXL045_P1_VDDA
R587  Q_RES  1K 1% CHIP  pkg 0402LF  page 250 : 1 = PCA9548_PCIE3_ADDR0 ; 2 = GND
R588  Q_RES  33 5% CHIP  pkg 0402LF  page 81 : 1 = SCM_USB_OC_R_N ; 2 = SCM_USB_OC_N
R589  Q_RES  0 5% CHIP  pkg 0402LF  page 29 : 1 = SCM_USB_OC_BU_R_N ; 2 = SCM_USB_OC_BUF_N
R590  Q_RES  4.7K 5% CHIP  pkg 0402LF  page 34 : 1 = P3V3_AUX ; 2 = SMB_CPU0_4_XLTR_SDA
R591  Q_RES  0 5% CHIP  pkg 0402LF  page 135 : 1 = P12V_OCP_SFF_BUF_EN_R ; 2 = P12V_OCP_EN_1_R2
R592  Q_RES  10K 1% CHIP  pkg 0402LF  page 183 : 1 = FM_9ZXL045_P1_2_OE_N ; 2 = GND
R593  Q_RES  10K 1% CHIP  pkg 0402LF  page 183 : 1 = FM_9ZXL045_P1_1_OE_N ; 2 = GND
R594  Q_RES  10K 1% CHIP  pkg 0402LF  page 183 : 1 = FM_9ZXL045_P1_0_OE_N ; 2 = GND
R595  Q_RES  0 5% CHIP  pkg 0201LF  page 276 : 1 = CLK_100M_RETIMER_CPU0_P0_R_DP ; 2 = CLK_100M_RETIMER_CPU0_P0_DP
R596  Q_RES  0 5% CHIP  pkg 0201LF  page 276 : 1 = CLK_100M_RETIMER_CPU0_P0_R_DN ; 2 = CLK_100M_RETIMER_CPU0_P0_DN
R597  Q_RES  0 5% CHIP  pkg 0201LF  page 331 : 1 = CLK_100M_RETIMER_CPU1_P1_R_DP ; 2 = CLK_100M_RETIMER_CPU1_P1_DP
R598  Q_RES  0 5% CHIP  pkg 0201LF  page 331 : 1 = CLK_100M_RETIMER_CPU1_P1_R_DN ; 2 = CLK_100M_RETIMER_CPU1_P1_DN
R599  Q_RES  0 5% CHIP  pkg 0201LF  page 320 : 1 = CLK_100M_RETIMER_CPU1_P0_R_DP ; 2 = CLK_100M_RETIMER_CPU1_P0_DP
R600  Q_RES  0 5% CHIP  pkg 0402LF  page 77 : 1 = SPI_CPU0_LVC3_CS1_N ; 2 = SPI_CPU0_LVC3_SCM_CS1_N
R601  Q_RES  1K 1% CHIP  pkg 0402LF  page 77 : 1 = PVDD18_S5_P0 ; 2 = SPI_CPU0_CS1_N
R602  Q_RES  33 5% CHIP  pkg 0402LF  page 77 : 1 = SPI_CPU0_LVC3_CLK ; 2 = SPI_CPU0_LVC3_SCM_CLK
R603  Q_RES  0 5% CHIP  pkg 0402LF  page 77 : 1 = SPI_CPU0_LVC3_CS0_N ; 2 = SPI_CPU0_LVC3_SCM_CS0_N
R604  Q_RES  33.2 1% CHIP  pkg 0402LF  page 77 : 1 = SPI_CPU0_LVC3_D0 ; 2 = SPI_CPU0_LVC3_SCM_D0
R605  Q_RES  49.9 1% CHIP  pkg 0402LF  page 77 : 1 = SPI_CPU0_LVC3_D1 ; 2 = SPI_CPU0_LVC3_SCM_D1
R606  Q_RES  0 5% CHIP  pkg 0402LF  page 77 : 1 = SPI_CPU0_LVC3_D2 ; 2 = SPI_CPU0_LVC3_SCM_D2
R607  Q_RES  0 5% CHIP  pkg 0402LF  page 77 : 1 = SPI_CPU0_LVC3_D3 ; 2 = SPI_CPU0_LVC3_SCM_D3
R608  Q_RES  33 5% CHIP  pkg 0402LF  page 77 : 1 = SPI_CPU0_LVC3_R_TPM_CS_N ; 2 = SPI_CPU0_LVC3_TPM_CS_N
R609  Q_RES  0 5% CHIP  pkg 0201LF  page 320 : 1 = CLK_100M_RETIMER_CPU1_P0_R_DN ; 2 = CLK_100M_RETIMER_CPU1_P0_DN
R610  Q_RES  1K 1% EMPTY  pkg 0402LF  page 77 : 1 = P3V3_AUX ; 2 = SPI_CPU0_LVC3_SCM_CS0_N
R611  Q_RES  0 5% CHIP  pkg 0201LF  page 287 : 1 = CLK_100M_RETIMER_CPU0_P1_R_DP ; 2 = CLK_100M_RETIMER_CPU0_P1_DP
R612  Q_RES  0 5% CHIP  pkg 0201LF  page 287 : 1 = CLK_100M_RETIMER_CPU0_P1_R_DN ; 2 = CLK_100M_RETIMER_CPU0_P1_DN
R613  Q_RES  0 5% CHIP  pkg 0201LF  page 298 : 1 = CLK_100M_RETIMER_CPU0_P2_R_DP ; 2 = CLK_100M_RETIMER_CPU0_P2_DP
R614  Q_RES  0 5% CHIP  pkg 0201LF  page 298 : 1 = CLK_100M_RETIMER_CPU0_P2_R_DN ; 2 = CLK_100M_RETIMER_CPU0_P2_DN
R615  Q_RES  0 5% CHIP  pkg 0201LF  page 309 : 1 = CLK_100M_RETIMER_CPU0_P3_R_DP ; 2 = CLK_100M_RETIMER_CPU0_P3_DP
R616  Q_RES  0 5% CHIP  pkg 0201LF  page 309 : 1 = CLK_100M_RETIMER_CPU0_P3_R_DN ; 2 = CLK_100M_RETIMER_CPU0_P3_DN
R617  Q_RES  4.7K 5% CHIP  pkg 0402LF  page 172 : 1 = PVDD18_S5_P0 ; 2 = JTAG_BMC_R_D_OE
